(kicad_pcb
	(version 20260206)
	(generator "pcbnew")
	(generator_version "10.0")
	(general
		(thickness 1.6)
		(legacy_teardrops no)
	)
	(paper "A4")
	(title_block
		(title "03242023_DA0F0TMBIJ0_F0T_Motherboard_J_brd_V01_OCP.brd")
		(comment 1 "Grand Teton / footprints 2708-2713 of 6105")
	)
	(layers
		(0 "F.Cu" signal "TOP")
		(4 "In1.Cu" signal "GND")
		(6 "In2.Cu" signal "IN1")
		(8 "In3.Cu" signal "GND1")
		(10 "In4.Cu" signal "IN2")
		(12 "In5.Cu" signal "GND2")
		(14 "In6.Cu" signal "IN3")
		(16 "In7.Cu" signal "GND3")
		(18 "In8.Cu" signal "VCC")
		(20 "In9.Cu" signal "VCC1")
		(22 "In10.Cu" signal "GND4")
		(24 "In11.Cu" signal "IN4")
		(26 "In12.Cu" signal "GND5")
		(28 "In13.Cu" signal "IN5")
		(30 "In14.Cu" signal "GND6")
		(32 "In15.Cu" signal "IN6")
		(34 "In16.Cu" signal "GND7")
		(2 "B.Cu" signal "BOTTOM")
		(9 "F.Adhes" user "F.Adhesive")
		(11 "B.Adhes" user "B.Adhesive")
		(13 "F.Paste" user "Package Geometry/Pastemask Top")
		(15 "B.Paste" user "Package Geometry/Pastemask Bottom")
		(5 "F.SilkS" user "Ref Des/Silkscreen Top")
		(7 "B.SilkS" user "Ref Des/Silkscreen Bottom")
		(1 "F.Mask" user "Board Geometry/Soldermask Top")
		(3 "B.Mask" user "Board Geometry/Soldermask Bottom")
		(17 "Dwgs.User" user "User.Drawings")
		(19 "Cmts.User" user "User.Comments")
		(21 "Eco1.User" user "User.Eco1")
		(23 "Eco2.User" user "User.Eco2")
		(25 "Edge.Cuts" user "Board Geometry/Outline")
		(27 "Margin" user)
		(31 "F.CrtYd" user "Package Geometry/Place Bound Top")
		(29 "B.CrtYd" user "Package Geometry/Place Bound Bottom")
		(35 "F.Fab" user "Ref Des/Assembly Top")
		(33 "B.Fab" user "Ref Des/Assembly Bottom")
	)
	(footprint ""
		(layer "F.Cu")
		(at 428.226474 -122.62866 180)
		(property "Reference" "PC624"
			(at 0 0 180)
			(layer "F.SilkS")
			(hide yes)
			(effects
				(font
					(size 1.27 1.27)
				)
			)
		)
		(property "Value" ""
			(at 0 0 180)
			(layer "F.Fab")
			(effects
				(font
					(size 1.27 1.27)
				)
			)
		)
		(duplicate_pad_numbers_are_jumpers no)
		(fp_line
			(start 0.7874 0.4064)
			(end -0.7874 0.4064)
			(stroke
				(width 0.1524)
				(type default)
			)
			(layer "F.SilkS")
		)
		(fp_line
			(start 0.7874 -0.4064)
			(end 0.7874 0.4064)
			(stroke
				(width 0.1524)
				(type default)
			)
			(layer "F.SilkS")
		)
		(fp_line
			(start -0.7874 0.4064)
			(end -0.7874 -0.4064)
			(stroke
				(width 0.1524)
				(type default)
			)
			(layer "F.SilkS")
		)
		(fp_line
			(start -0.7874 -0.4064)
			(end 0.7874 -0.4064)
			(stroke
				(width 0.1524)
				(type default)
			)
			(layer "F.SilkS")
		)
		(fp_line
			(start 0.67945 0.3048)
			(end 0.120396 0.3048)
			(stroke
				(width 0.1)
				(type default)
			)
			(layer "F.Fab")
		)
		(fp_line
			(start 0.67945 -0.3048)
			(end 0.67945 0.3048)
			(stroke
				(width 0.1)
				(type default)
			)
			(layer "F.Fab")
		)
		(fp_line
			(start 0.12065 -0.2794)
			(end 0.12065 -0.3048)
			(stroke
				(width 0.1)
				(type default)
			)
			(layer "F.Fab")
		)
		(fp_line
			(start 0.12065 -0.3048)
			(end 0.67945 -0.3048)
			(stroke
				(width 0.1)
				(type default)
			)
			(layer "F.Fab")
		)
		(fp_line
			(start 0.120396 0.3048)
			(end 0.120396 0.2794)
			(stroke
				(width 0.1)
				(type default)
			)
			(layer "F.Fab")
		)
		(fp_line
			(start 0.120396 0.2794)
			(end -0.12065 0.2794)
			(stroke
				(width 0.1)
				(type default)
			)
			(layer "F.Fab")
		)
		(fp_line
			(start -0.12065 0.3048)
			(end -0.67945 0.3048)
			(stroke
				(width 0.1)
				(type default)
			)
			(layer "F.Fab")
		)
		(fp_line
			(start -0.12065 0.2794)
			(end -0.12065 0.3048)
			(stroke
				(width 0.1)
				(type default)
			)
			(layer "F.Fab")
		)
		(fp_line
			(start -0.12065 -0.2794)
			(end 0.12065 -0.2794)
			(stroke
				(width 0.1)
				(type default)
			)
			(layer "F.Fab")
		)
		(fp_line
			(start -0.12065 -0.305054)
			(end -0.12065 -0.2794)
			(stroke
				(width 0.1)
				(type default)
			)
			(layer "F.Fab")
		)
		(fp_line
			(start -0.67945 0.3048)
			(end -0.67945 -0.305054)
			(stroke
				(width 0.1)
				(type default)
			)
			(layer "F.Fab")
		)
		(fp_line
			(start -0.67945 -0.305054)
			(end -0.12065 -0.305054)
			(stroke
				(width 0.1)
				(type default)
			)
			(layer "F.Fab")
		)
		(pad "1" smd circle
			(at -0.40005 0 180)
			(size 0 0)
			(layers "F.Cu" "F.Mask" "F.Paste")
			(net "PVCCD_HV_CPU0_ISENSE_P")
		)
		(pad "2" smd circle
			(at 0.40005 0 180)
			(size 0 0)
			(layers "F.Cu" "F.Mask" "F.Paste")
			(net "GND")
		)
	)
	(footprint ""
		(layer "F.Cu")
		(at 320.241422 -63.896748)
		(property "Reference" "R1249"
			(at 0 0 0)
			(layer "F.SilkS")
			(hide yes)
			(effects
				(font
					(size 1.27 1.27)
				)
			)
		)
		(property "Value" ""
			(at 0 0 0)
			(layer "F.Fab")
			(effects
				(font
					(size 1.27 1.27)
				)
			)
		)
		(duplicate_pad_numbers_are_jumpers no)
		(fp_line
			(start -0.7874 -0.4064)
			(end 0.7874 -0.4064)
			(stroke
				(width 0.1524)
				(type default)
			)
			(layer "F.SilkS")
		)
		(fp_line
			(start -0.7874 0.4064)
			(end -0.7874 -0.4064)
			(stroke
				(width 0.1524)
				(type default)
			)
			(layer "F.SilkS")
		)
		(fp_line
			(start 0.7874 -0.4064)
			(end 0.7874 0.4064)
			(stroke
				(width 0.1524)
				(type default)
			)
			(layer "F.SilkS")
		)
		(fp_line
			(start 0.7874 0.4064)
			(end -0.7874 0.4064)
			(stroke
				(width 0.1524)
				(type default)
			)
			(layer "F.SilkS")
		)
		(fp_line
			(start -0.67945 -0.305054)
			(end -0.12065 -0.305054)
			(stroke
				(width 0.1)
				(type default)
			)
			(layer "F.Fab")
		)
		(fp_line
			(start -0.67945 0.3048)
			(end -0.67945 -0.305054)
			(stroke
				(width 0.1)
				(type default)
			)
			(layer "F.Fab")
		)
		(fp_line
			(start -0.12065 -0.305054)
			(end -0.12065 -0.2794)
			(stroke
				(width 0.1)
				(type default)
			)
			(layer "F.Fab")
		)
		(fp_line
			(start -0.12065 -0.2794)
			(end 0.12065 -0.2794)
			(stroke
				(width 0.1)
				(type default)
			)
			(layer "F.Fab")
		)
		(fp_line
			(start -0.12065 0.2794)
			(end -0.12065 0.3048)
			(stroke
				(width 0.1)
				(type default)
			)
			(layer "F.Fab")
		)
		(fp_line
			(start -0.12065 0.3048)
			(end -0.67945 0.3048)
			(stroke
				(width 0.1)
				(type default)
			)
			(layer "F.Fab")
		)
		(fp_line
			(start 0.120396 0.2794)
			(end -0.12065 0.2794)
			(stroke
				(width 0.1)
				(type default)
			)
			(layer "F.Fab")
		)
		(fp_line
			(start 0.120396 0.3048)
			(end 0.120396 0.2794)
			(stroke
				(width 0.1)
				(type default)
			)
			(layer "F.Fab")
		)
		(fp_line
			(start 0.12065 -0.3048)
			(end 0.67945 -0.3048)
			(stroke
				(width 0.1)
				(type default)
			)
			(layer "F.Fab")
		)
		(fp_line
			(start 0.12065 -0.2794)
			(end 0.12065 -0.3048)
			(stroke
				(width 0.1)
				(type default)
			)
			(layer "F.Fab")
		)
		(fp_line
			(start 0.67945 -0.3048)
			(end 0.67945 0.3048)
			(stroke
				(width 0.1)
				(type default)
			)
			(layer "F.Fab")
		)
		(fp_line
			(start 0.67945 0.3048)
			(end 0.120396 0.3048)
			(stroke
				(width 0.1)
				(type default)
			)
			(layer "F.Fab")
		)
		(pad "1" smd circle
			(at -0.40005 0)
			(size 0 0)
			(layers "F.Cu" "F.Mask" "F.Paste")
			(net "FM_THERMTRIP_DLY_LVC1_N")
		)
		(pad "2" smd circle
			(at 0.40005 0)
			(size 0 0)
			(layers "F.Cu" "F.Mask" "F.Paste")
			(net "H_THERMTRIP_LVC1_N")
		)
	)
	(footprint ""
		(layer "F.Cu")
		(at 205.397608 -404.823422)
		(property "Reference" "PC2182"
			(at 0 0 0)
			(layer "F.SilkS")
			(hide yes)
			(effects
				(font
					(size 1.27 1.27)
				)
			)
		)
		(property "Value" ""
			(at 0 0 0)
			(layer "F.Fab")
			(effects
				(font
					(size 1.27 1.27)
				)
			)
		)
		(duplicate_pad_numbers_are_jumpers no)
		(fp_line
			(start -0.7874 -0.4064)
			(end 0.7874 -0.4064)
			(stroke
				(width 0.1524)
				(type default)
			)
			(layer "F.SilkS")
		)
		(fp_line
			(start -0.7874 0.4064)
			(end -0.7874 -0.4064)
			(stroke
				(width 0.1524)
				(type default)
			)
			(layer "F.SilkS")
		)
		(fp_line
			(start 0.7874 -0.4064)
			(end 0.7874 0.4064)
			(stroke
				(width 0.1524)
				(type default)
			)
			(layer "F.SilkS")
		)
		(fp_line
			(start 0.7874 0.4064)
			(end -0.7874 0.4064)
			(stroke
				(width 0.1524)
				(type default)
			)
			(layer "F.SilkS")
		)
		(fp_line
			(start -0.67945 -0.305054)
			(end -0.12065 -0.305054)
			(stroke
				(width 0.1)
				(type default)
			)
			(layer "F.Fab")
		)
		(fp_line
			(start -0.67945 0.3048)
			(end -0.67945 -0.305054)
			(stroke
				(width 0.1)
				(type default)
			)
			(layer "F.Fab")
		)
		(fp_line
			(start -0.12065 -0.305054)
			(end -0.12065 -0.2794)
			(stroke
				(width 0.1)
				(type default)
			)
			(layer "F.Fab")
		)
		(fp_line
			(start -0.12065 -0.2794)
			(end 0.12065 -0.2794)
			(stroke
				(width 0.1)
				(type default)
			)
			(layer "F.Fab")
		)
		(fp_line
			(start -0.12065 0.2794)
			(end -0.12065 0.3048)
			(stroke
				(width 0.1)
				(type default)
			)
			(layer "F.Fab")
		)
		(fp_line
			(start -0.12065 0.3048)
			(end -0.67945 0.3048)
			(stroke
				(width 0.1)
				(type default)
			)
			(layer "F.Fab")
		)
		(fp_line
			(start 0.120396 0.2794)
			(end -0.12065 0.2794)
			(stroke
				(width 0.1)
				(type default)
			)
			(layer "F.Fab")
		)
		(fp_line
			(start 0.120396 0.3048)
			(end 0.120396 0.2794)
			(stroke
				(width 0.1)
				(type default)
			)
			(layer "F.Fab")
		)
		(fp_line
			(start 0.12065 -0.3048)
			(end 0.67945 -0.3048)
			(stroke
				(width 0.1)
				(type default)
			)
			(layer "F.Fab")
		)
		(fp_line
			(start 0.12065 -0.2794)
			(end 0.12065 -0.3048)
			(stroke
				(width 0.1)
				(type default)
			)
			(layer "F.Fab")
		)
		(fp_line
			(start 0.67945 -0.3048)
			(end 0.67945 0.3048)
			(stroke
				(width 0.1)
				(type default)
			)
			(layer "F.Fab")
		)
		(fp_line
			(start 0.67945 0.3048)
			(end 0.120396 0.3048)
			(stroke
				(width 0.1)
				(type default)
			)
			(layer "F.Fab")
		)
		(pad "1" smd circle
			(at -0.40005 0)
			(size 0 0)
			(layers "F.Cu" "F.Mask" "F.Paste")
			(net "HSC_ON")
		)
		(pad "2" smd circle
			(at 0.40005 0)
			(size 0 0)
			(layers "F.Cu" "F.Mask" "F.Paste")
			(net "AGND_HSC")
		)
	)
	(footprint ""
		(layer "F.Cu")
		(at 462.143094 -38.684454 90)
		(property "Reference" "R4061"
			(at 0 0 90)
			(layer "F.SilkS")
			(hide yes)
			(effects
				(font
					(size 1.27 1.27)
				)
			)
		)
		(property "Value" ""
			(at 0 0 90)
			(layer "F.Fab")
			(effects
				(font
					(size 1.27 1.27)
				)
			)
		)
		(duplicate_pad_numbers_are_jumpers no)
		(fp_line
			(start 0.7874 -0.4064)
			(end 0.7874 0.4064)
			(stroke
				(width 0.1524)
				(type default)
			)
			(layer "F.SilkS")
		)
		(fp_line
			(start -0.7874 -0.4064)
			(end 0.7874 -0.4064)
			(stroke
				(width 0.1524)
				(type default)
			)
			(layer "F.SilkS")
		)
		(fp_line
			(start 0.7874 0.4064)
			(end -0.7874 0.4064)
			(stroke
				(width 0.1524)
				(type default)
			)
			(layer "F.SilkS")
		)
		(fp_line
			(start -0.7874 0.4064)
			(end -0.7874 -0.4064)
			(stroke
				(width 0.1524)
				(type default)
			)
			(layer "F.SilkS")
		)
		(fp_line
			(start -0.12065 -0.305054)
			(end -0.12065 -0.2794)
			(stroke
				(width 0.1)
				(type default)
			)
			(layer "F.Fab")
		)
		(fp_line
			(start -0.67945 -0.305054)
			(end -0.12065 -0.305054)
			(stroke
				(width 0.1)
				(type default)
			)
			(layer "F.Fab")
		)
		(fp_line
			(start 0.67945 -0.3048)
			(end 0.67945 0.3048)
			(stroke
				(width 0.1)
				(type default)
			)
			(layer "F.Fab")
		)
		(fp_line
			(start 0.12065 -0.3048)
			(end 0.67945 -0.3048)
			(stroke
				(width 0.1)
				(type default)
			)
			(layer "F.Fab")
		)
		(fp_line
			(start 0.12065 -0.2794)
			(end 0.12065 -0.3048)
			(stroke
				(width 0.1)
				(type default)
			)
			(layer "F.Fab")
		)
		(fp_line
			(start -0.12065 -0.2794)
			(end 0.12065 -0.2794)
			(stroke
				(width 0.1)
				(type default)
			)
			(layer "F.Fab")
		)
		(fp_line
			(start 0.120396 0.2794)
			(end -0.12065 0.2794)
			(stroke
				(width 0.1)
				(type default)
			)
			(layer "F.Fab")
		)
		(fp_line
			(start -0.12065 0.2794)
			(end -0.12065 0.3048)
			(stroke
				(width 0.1)
				(type default)
			)
			(layer "F.Fab")
		)
		(fp_line
			(start 0.67945 0.3048)
			(end 0.120396 0.3048)
			(stroke
				(width 0.1)
				(type default)
			)
			(layer "F.Fab")
		)
		(fp_line
			(start 0.120396 0.3048)
			(end 0.120396 0.2794)
			(stroke
				(width 0.1)
				(type default)
			)
			(layer "F.Fab")
		)
		(fp_line
			(start -0.12065 0.3048)
			(end -0.67945 0.3048)
			(stroke
				(width 0.1)
				(type default)
			)
			(layer "F.Fab")
		)
		(fp_line
			(start -0.67945 0.3048)
			(end -0.67945 -0.305054)
			(stroke
				(width 0.1)
				(type default)
			)
			(layer "F.Fab")
		)
		(pad "1" smd circle
			(at -0.40005 0 90)
			(size 0 0)
			(layers "F.Cu" "F.Mask" "F.Paste")
			(net "HP_LVC3_OCP_V3_1_EN")
		)
		(pad "2" smd circle
			(at 0.40005 0 90)
			(size 0 0)
			(layers "F.Cu" "F.Mask" "F.Paste")
			(net "P12V_OCP_EN_1_R")
		)
	)
	(footprint ""
		(layer "F.Cu")
		(at 160.83788 -108.295948)
		(property "Reference" "R3230"
			(at 0 0 0)
			(layer "F.SilkS")
			(hide yes)
			(effects
				(font
					(size 1.27 1.27)
				)
			)
		)
		(property "Value" ""
			(at 0 0 0)
			(layer "F.Fab")
			(effects
				(font
					(size 1.27 1.27)
				)
			)
		)
		(duplicate_pad_numbers_are_jumpers no)
		(fp_line
			(start -0.7874 -0.4064)
			(end 0.7874 -0.4064)
			(stroke
				(width 0.1524)
				(type default)
			)
			(layer "F.SilkS")
		)
		(fp_line
			(start -0.7874 0.4064)
			(end -0.7874 -0.4064)
			(stroke
				(width 0.1524)
				(type default)
			)
			(layer "F.SilkS")
		)
		(fp_line
			(start 0.7874 -0.4064)
			(end 0.7874 0.4064)
			(stroke
				(width 0.1524)
				(type default)
			)
			(layer "F.SilkS")
		)
		(fp_line
			(start 0.7874 0.4064)
			(end -0.7874 0.4064)
			(stroke
				(width 0.1524)
				(type default)
			)
			(layer "F.SilkS")
		)
		(fp_line
			(start -0.67945 -0.305054)
			(end -0.12065 -0.305054)
			(stroke
				(width 0.1)
				(type default)
			)
			(layer "F.Fab")
		)
		(fp_line
			(start -0.67945 0.3048)
			(end -0.67945 -0.305054)
			(stroke
				(width 0.1)
				(type default)
			)
			(layer "F.Fab")
		)
		(fp_line
			(start -0.12065 -0.305054)
			(end -0.12065 -0.2794)
			(stroke
				(width 0.1)
				(type default)
			)
			(layer "F.Fab")
		)
		(fp_line
			(start -0.12065 -0.2794)
			(end 0.12065 -0.2794)
			(stroke
				(width 0.1)
				(type default)
			)
			(layer "F.Fab")
		)
		(fp_line
			(start -0.12065 0.2794)
			(end -0.12065 0.3048)
			(stroke
				(width 0.1)
				(type default)
			)
			(layer "F.Fab")
		)
		(fp_line
			(start -0.12065 0.3048)
			(end -0.67945 0.3048)
			(stroke
				(width 0.1)
				(type default)
			)
			(layer "F.Fab")
		)
		(fp_line
			(start 0.120396 0.2794)
			(end -0.12065 0.2794)
			(stroke
				(width 0.1)
				(type default)
			)
			(layer "F.Fab")
		)
		(fp_line
			(start 0.120396 0.3048)
			(end 0.120396 0.2794)
			(stroke
				(width 0.1)
				(type default)
			)
			(layer "F.Fab")
		)
		(fp_line
			(start 0.12065 -0.3048)
			(end 0.67945 -0.3048)
			(stroke
				(width 0.1)
				(type default)
			)
			(layer "F.Fab")
		)
		(fp_line
			(start 0.12065 -0.2794)
			(end 0.12065 -0.3048)
			(stroke
				(width 0.1)
				(type default)
			)
			(layer "F.Fab")
		)
		(fp_line
			(start 0.67945 -0.3048)
			(end 0.67945 0.3048)
			(stroke
				(width 0.1)
				(type default)
			)
			(layer "F.Fab")
		)
		(fp_line
			(start 0.67945 0.3048)
			(end 0.120396 0.3048)
			(stroke
				(width 0.1)
				(type default)
			)
			(layer "F.Fab")
		)
		(pad "1" smd circle
			(at -0.40005 0)
			(size 0 0)
			(layers "F.Cu" "F.Mask" "F.Paste")
			(net "FM_OCP_V3_2_PWR_GOOD")
		)
		(pad "2" smd circle
			(at 0.40005 0)
			(size 0 0)
			(layers "F.Cu" "F.Mask" "F.Paste")
			(net "FM_OCP_V3_2_PWR_GOOD_R")
		)
	)
	(footprint ""
		(layer "F.Cu")
		(at 97.992438 -354.88499 -90)
		(property "Reference" "PC1656"
			(at 0 0 270)
			(layer "F.SilkS")
			(hide yes)
			(effects
				(font
					(size 1.27 1.27)
				)
			)
		)
		(property "Value" ""
			(at 0 0 270)
			(layer "F.Fab")
			(effects
				(font
					(size 1.27 1.27)
				)
			)
		)
		(duplicate_pad_numbers_are_jumpers no)
		(fp_line
			(start -0.7874 0.4064)
			(end -0.7874 -0.4064)
			(stroke
				(width 0.1524)
				(type default)
			)
			(layer "F.SilkS")
		)
		(fp_line
			(start 0.7874 0.4064)
			(end -0.7874 0.4064)
			(stroke
				(width 0.1524)
				(type default)
			)
			(layer "F.SilkS")
		)
		(fp_line
			(start -0.7874 -0.4064)
			(end 0.7874 -0.4064)
			(stroke
				(width 0.1524)
				(type default)
			)
			(layer "F.SilkS")
		)
		(fp_line
			(start 0.7874 -0.4064)
			(end 0.7874 0.4064)
			(stroke
				(width 0.1524)
				(type default)
			)
			(layer "F.SilkS")
		)
		(fp_line
			(start -0.67945 0.3048)
			(end -0.67945 -0.305054)
			(stroke
				(width 0.1)
				(type default)
			)
			(layer "F.Fab")
		)
		(fp_line
			(start -0.12065 0.3048)
			(end -0.67945 0.3048)
			(stroke
				(width 0.1)
				(type default)
			)
			(layer "F.Fab")
		)
		(fp_line
			(start 0.120396 0.3048)
			(end 0.120396 0.2794)
			(stroke
				(width 0.1)
				(type default)
			)
			(layer "F.Fab")
		)
		(fp_line
			(start 0.67945 0.3048)
			(end 0.120396 0.3048)
			(stroke
				(width 0.1)
				(type default)
			)
			(layer "F.Fab")
		)
		(fp_line
			(start -0.12065 0.2794)
			(end -0.12065 0.3048)
			(stroke
				(width 0.1)
				(type default)
			)
			(layer "F.Fab")
		)
		(fp_line
			(start 0.120396 0.2794)
			(end -0.12065 0.2794)
			(stroke
				(width 0.1)
				(type default)
			)
			(layer "F.Fab")
		)
		(fp_line
			(start -0.12065 -0.2794)
			(end 0.12065 -0.2794)
			(stroke
				(width 0.1)
				(type default)
			)
			(layer "F.Fab")
		)
		(fp_line
			(start 0.12065 -0.2794)
			(end 0.12065 -0.3048)
			(stroke
				(width 0.1)
				(type default)
			)
			(layer "F.Fab")
		)
		(fp_line
			(start 0.12065 -0.3048)
			(end 0.67945 -0.3048)
			(stroke
				(width 0.1)
				(type default)
			)
			(layer "F.Fab")
		)
		(fp_line
			(start 0.67945 -0.3048)
			(end 0.67945 0.3048)
			(stroke
				(width 0.1)
				(type default)
			)
			(layer "F.Fab")
		)
		(fp_line
			(start -0.67945 -0.305054)
			(end -0.12065 -0.305054)
			(stroke
				(width 0.1)
				(type default)
			)
			(layer "F.Fab")
		)
		(fp_line
			(start -0.12065 -0.305054)
			(end -0.12065 -0.2794)
			(stroke
				(width 0.1)
				(type default)
			)
			(layer "F.Fab")
		)
		(pad "1" smd circle
			(at -0.40005 0 270)
			(size 0 0)
			(layers "F.Cu" "F.Mask" "F.Paste")
			(net "P12V_AUX")
		)
		(pad "2" smd circle
			(at 0.40005 0 270)
			(size 0 0)
			(layers "F.Cu" "F.Mask" "F.Paste")
			(net "GND")
		)
	)
)
